(kicad_pcb
	(version 20260206)
	(generator "pcbnew")
	(generator_version "10.0")
	(general
		(thickness 1.6)
		(legacy_teardrops no)
	)
	(paper "A4")
	(title_block
		(title "01162023_DA0F0TEBIF0_F0T_Expander_BD_F_brd_V02_OCP.brd")
		(comment 1 "Grand Teton / footprints 7276-7286 of 9728")
	)
	(layers
		(0 "F.Cu" signal "TOP")
		(4 "In1.Cu" signal "GND")
		(6 "In2.Cu" signal "VCC")
		(8 "In3.Cu" signal "VCC1")
		(10 "In4.Cu" signal "GND1")
		(12 "In5.Cu" signal "IN1")
		(14 "In6.Cu" signal "GND2")
		(16 "In7.Cu" signal "IN2")
		(18 "In8.Cu" signal "GND3")
		(20 "In9.Cu" signal "IN3")
		(22 "In10.Cu" signal "GND4")
		(24 "In11.Cu" signal "IN4")
		(26 "In12.Cu" signal "GND5")
		(28 "In13.Cu" signal "IN5")
		(30 "In14.Cu" signal "GND6")
		(32 "In15.Cu" signal "IN6")
		(34 "In16.Cu" signal "GND7")
		(2 "B.Cu" signal "BOTTOM")
		(9 "F.Adhes" user "F.Adhesive")
		(11 "B.Adhes" user "B.Adhesive")
		(13 "F.Paste" user "Package Geometry/Pastemask Top")
		(15 "B.Paste" user "Package Geometry/Pastemask Bottom")
		(5 "F.SilkS" user "Ref Des/Silkscreen Top")
		(7 "B.SilkS" user "Ref Des/Silkscreen Bottom")
		(1 "F.Mask" user "Board Geometry/Soldermask Top")
		(3 "B.Mask" user "Board Geometry/Soldermask Bottom")
		(17 "Dwgs.User" user "User.Drawings")
		(19 "Cmts.User" user "User.Comments")
		(21 "Eco1.User" user "User.Eco1")
		(23 "Eco2.User" user "User.Eco2")
		(25 "Edge.Cuts" user "Board Geometry/Outline")
		(27 "Margin" user)
		(31 "F.CrtYd" user "Package Geometry/Place Bound Top")
		(29 "B.CrtYd" user "Package Geometry/Place Bound Bottom")
		(35 "F.Fab" user "Ref Des/Assembly Top")
		(33 "B.Fab" user "Ref Des/Assembly Bottom")
	)
	(footprint ""
		(layer "B.Cu")
		(at 286.149796 -299.699934 -90)
		(property "Reference" "C1710"
			(at 0 0 90)
			(layer "B.SilkS")
			(hide yes)
			(effects
				(font
					(size 1.27 1.27)
				)
				(justify mirror)
			)
		)
		(property "Value" ""
			(at 0 0 90)
			(layer "B.Fab")
			(effects
				(font
					(size 1.27 1.27)
				)
				(justify mirror)
			)
		)
		(duplicate_pad_numbers_are_jumpers no)
		(fp_line
			(start -0.299974 0.150114)
			(end 0.299974 0.150114)
			(stroke
				(width 0.1)
				(type default)
			)
			(layer "B.Fab")
		)
		(fp_line
			(start 0.299974 0.150114)
			(end 0.299974 -0.150114)
			(stroke
				(width 0.1)
				(type default)
			)
			(layer "B.Fab")
		)
		(fp_line
			(start -0.299974 -0.150114)
			(end -0.299974 0.150114)
			(stroke
				(width 0.1)
				(type default)
			)
			(layer "B.Fab")
		)
		(fp_line
			(start 0.299974 -0.150114)
			(end -0.299974 -0.150114)
			(stroke
				(width 0.1)
				(type default)
			)
			(layer "B.Fab")
		)
		(pad "1" smd rect
			(at 0.2667 0 90)
			(size 0.3048 0.381)
			(layers "B.Cu" "B.Mask" "B.Paste")
			(net "P0V8_SERDES_VDDA_PEX2")
		)
		(pad "2" smd rect
			(at -0.2667 0 90)
			(size 0.3048 0.381)
			(layers "B.Cu" "B.Mask" "B.Paste")
			(net "GND")
		)
	)
	(footprint ""
		(layer "B.Cu")
		(at 299.005244 -236.736636 90)
		(property "Reference" "R6174"
			(at 0 0 90)
			(layer "B.SilkS")
			(hide yes)
			(effects
				(font
					(size 1.27 1.27)
				)
				(justify mirror)
			)
		)
		(property "Value" ""
			(at 0 0 90)
			(layer "B.Fab")
			(effects
				(font
					(size 1.27 1.27)
				)
				(justify mirror)
			)
		)
		(duplicate_pad_numbers_are_jumpers no)
		(fp_line
			(start 0.7874 -0.4064)
			(end -0.7874 -0.4064)
			(stroke
				(width 0.1524)
				(type default)
			)
			(layer "B.SilkS")
		)
		(fp_line
			(start -0.7874 -0.4064)
			(end -0.7874 0.4064)
			(stroke
				(width 0.1524)
				(type default)
			)
			(layer "B.SilkS")
		)
		(fp_line
			(start 0.7874 0.4064)
			(end 0.7874 -0.4064)
			(stroke
				(width 0.1524)
				(type default)
			)
			(layer "B.SilkS")
		)
		(fp_line
			(start -0.7874 0.4064)
			(end 0.7874 0.4064)
			(stroke
				(width 0.1524)
				(type default)
			)
			(layer "B.SilkS")
		)
		(fp_line
			(start 0.67945 -0.305054)
			(end 0.12065 -0.305054)
			(stroke
				(width 0.1)
				(type default)
			)
			(layer "B.Fab")
		)
		(fp_line
			(start 0.12065 -0.305054)
			(end 0.12065 -0.2794)
			(stroke
				(width 0.1)
				(type default)
			)
			(layer "B.Fab")
		)
		(fp_line
			(start -0.12065 -0.3048)
			(end -0.67945 -0.3048)
			(stroke
				(width 0.1)
				(type default)
			)
			(layer "B.Fab")
		)
		(fp_line
			(start -0.67945 -0.3048)
			(end -0.67945 0.3048)
			(stroke
				(width 0.1)
				(type default)
			)
			(layer "B.Fab")
		)
		(fp_line
			(start 0.12065 -0.2794)
			(end -0.12065 -0.2794)
			(stroke
				(width 0.1)
				(type default)
			)
			(layer "B.Fab")
		)
		(fp_line
			(start -0.12065 -0.2794)
			(end -0.12065 -0.3048)
			(stroke
				(width 0.1)
				(type default)
			)
			(layer "B.Fab")
		)
		(fp_line
			(start 0.12065 0.2794)
			(end 0.12065 0.3048)
			(stroke
				(width 0.1)
				(type default)
			)
			(layer "B.Fab")
		)
		(fp_line
			(start -0.120396 0.2794)
			(end 0.12065 0.2794)
			(stroke
				(width 0.1)
				(type default)
			)
			(layer "B.Fab")
		)
		(fp_line
			(start 0.67945 0.3048)
			(end 0.67945 -0.305054)
			(stroke
				(width 0.1)
				(type default)
			)
			(layer "B.Fab")
		)
		(fp_line
			(start 0.12065 0.3048)
			(end 0.67945 0.3048)
			(stroke
				(width 0.1)
				(type default)
			)
			(layer "B.Fab")
		)
		(fp_line
			(start -0.120396 0.3048)
			(end -0.120396 0.2794)
			(stroke
				(width 0.1)
				(type default)
			)
			(layer "B.Fab")
		)
		(fp_line
			(start -0.67945 0.3048)
			(end -0.120396 0.3048)
			(stroke
				(width 0.1)
				(type default)
			)
			(layer "B.Fab")
		)
		(pad "1" smd circle
			(at 0.40005 0 270)
			(size 0 0)
			(layers "B.Cu" "B.Mask" "B.Paste")
			(net "GND")
		)
		(pad "2" smd circle
			(at -0.40005 0 270)
			(size 0 0)
			(layers "B.Cu" "B.Mask" "B.Paste")
			(net "RST_GPU_PERST_0_N")
		)
	)
	(footprint ""
		(layer "B.Cu")
		(at 66.299842 -301.599854 -90)
		(property "Reference" "C1196"
			(at 0 0 90)
			(layer "B.SilkS")
			(hide yes)
			(effects
				(font
					(size 1.27 1.27)
				)
				(justify mirror)
			)
		)
		(property "Value" ""
			(at 0 0 90)
			(layer "B.Fab")
			(effects
				(font
					(size 1.27 1.27)
				)
				(justify mirror)
			)
		)
		(duplicate_pad_numbers_are_jumpers no)
		(fp_line
			(start -0.299974 0.150114)
			(end 0.299974 0.150114)
			(stroke
				(width 0.1)
				(type default)
			)
			(layer "B.Fab")
		)
		(fp_line
			(start 0.299974 0.150114)
			(end 0.299974 -0.150114)
			(stroke
				(width 0.1)
				(type default)
			)
			(layer "B.Fab")
		)
		(fp_line
			(start -0.299974 -0.150114)
			(end -0.299974 0.150114)
			(stroke
				(width 0.1)
				(type default)
			)
			(layer "B.Fab")
		)
		(fp_line
			(start 0.299974 -0.150114)
			(end -0.299974 -0.150114)
			(stroke
				(width 0.1)
				(type default)
			)
			(layer "B.Fab")
		)
		(pad "1" smd rect
			(at 0.2667 0 90)
			(size 0.3048 0.381)
			(layers "B.Cu" "B.Mask" "B.Paste")
			(net "P0V8_SERDES_VDDA_PEX0")
		)
		(pad "2" smd rect
			(at -0.2667 0 90)
			(size 0.3048 0.381)
			(layers "B.Cu" "B.Mask" "B.Paste")
			(net "GND")
		)
	)
	(footprint ""
		(layer "B.Cu")
		(at 351.645982 -155.321 180)
		(property "Reference" "R4791"
			(at 0 0 0)
			(layer "B.SilkS")
			(hide yes)
			(effects
				(font
					(size 1.27 1.27)
				)
				(justify mirror)
			)
		)
		(property "Value" ""
			(at 0 0 0)
			(layer "B.Fab")
			(effects
				(font
					(size 1.27 1.27)
				)
				(justify mirror)
			)
		)
		(duplicate_pad_numbers_are_jumpers no)
		(fp_line
			(start 0.7874 0.4064)
			(end 0.7874 -0.4064)
			(stroke
				(width 0.1524)
				(type default)
			)
			(layer "B.SilkS")
		)
		(fp_line
			(start 0.7874 -0.4064)
			(end -0.7874 -0.4064)
			(stroke
				(width 0.1524)
				(type default)
			)
			(layer "B.SilkS")
		)
		(fp_line
			(start -0.7874 0.4064)
			(end 0.7874 0.4064)
			(stroke
				(width 0.1524)
				(type default)
			)
			(layer "B.SilkS")
		)
		(fp_line
			(start -0.7874 -0.4064)
			(end -0.7874 0.4064)
			(stroke
				(width 0.1524)
				(type default)
			)
			(layer "B.SilkS")
		)
		(fp_line
			(start 0.67945 0.3048)
			(end 0.67945 -0.305054)
			(stroke
				(width 0.1)
				(type default)
			)
			(layer "B.Fab")
		)
		(fp_line
			(start 0.67945 -0.305054)
			(end 0.12065 -0.305054)
			(stroke
				(width 0.1)
				(type default)
			)
			(layer "B.Fab")
		)
		(fp_line
			(start 0.12065 0.3048)
			(end 0.67945 0.3048)
			(stroke
				(width 0.1)
				(type default)
			)
			(layer "B.Fab")
		)
		(fp_line
			(start 0.12065 0.2794)
			(end 0.12065 0.3048)
			(stroke
				(width 0.1)
				(type default)
			)
			(layer "B.Fab")
		)
		(fp_line
			(start 0.12065 -0.2794)
			(end -0.12065 -0.2794)
			(stroke
				(width 0.1)
				(type default)
			)
			(layer "B.Fab")
		)
		(fp_line
			(start 0.12065 -0.305054)
			(end 0.12065 -0.2794)
			(stroke
				(width 0.1)
				(type default)
			)
			(layer "B.Fab")
		)
		(fp_line
			(start -0.120396 0.3048)
			(end -0.120396 0.2794)
			(stroke
				(width 0.1)
				(type default)
			)
			(layer "B.Fab")
		)
		(fp_line
			(start -0.120396 0.2794)
			(end 0.12065 0.2794)
			(stroke
				(width 0.1)
				(type default)
			)
			(layer "B.Fab")
		)
		(fp_line
			(start -0.12065 -0.2794)
			(end -0.12065 -0.3048)
			(stroke
				(width 0.1)
				(type default)
			)
			(layer "B.Fab")
		)
		(fp_line
			(start -0.12065 -0.3048)
			(end -0.67945 -0.3048)
			(stroke
				(width 0.1)
				(type default)
			)
			(layer "B.Fab")
		)
		(fp_line
			(start -0.67945 0.3048)
			(end -0.120396 0.3048)
			(stroke
				(width 0.1)
				(type default)
			)
			(layer "B.Fab")
		)
		(fp_line
			(start -0.67945 -0.3048)
			(end -0.67945 0.3048)
			(stroke
				(width 0.1)
				(type default)
			)
			(layer "B.Fab")
		)
		(pad "1" smd circle
			(at 0.40005 0)
			(size 0 0)
			(layers "B.Cu" "B.Mask" "B.Paste")
			(net "P3V3_AUX")
		)
		(pad "2" smd circle
			(at -0.40005 0)
			(size 0 0)
			(layers "B.Cu" "B.Mask" "B.Paste")
			(net "NIC6_PEX_PWR_EN_R")
		)
	)
	(footprint ""
		(layer "B.Cu")
		(at 305.6001 -110.978696)
		(property "Reference" "C926"
			(at 0 0 0)
			(layer "B.SilkS")
			(hide yes)
			(effects
				(font
					(size 1.27 1.27)
				)
				(justify mirror)
			)
		)
		(property "Value" ""
			(at 0 0 0)
			(layer "B.Fab")
			(effects
				(font
					(size 1.27 1.27)
				)
				(justify mirror)
			)
		)
		(duplicate_pad_numbers_are_jumpers no)
		(fp_line
			(start -0.299974 -0.150114)
			(end -0.299974 0.150114)
			(stroke
				(width 0.1)
				(type default)
			)
			(layer "B.Fab")
		)
		(fp_line
			(start -0.299974 0.150114)
			(end 0.299974 0.150114)
			(stroke
				(width 0.1)
				(type default)
			)
			(layer "B.Fab")
		)
		(fp_line
			(start 0.299974 -0.150114)
			(end -0.299974 -0.150114)
			(stroke
				(width 0.1)
				(type default)
			)
			(layer "B.Fab")
		)
		(fp_line
			(start 0.299974 0.150114)
			(end 0.299974 -0.150114)
			(stroke
				(width 0.1)
				(type default)
			)
			(layer "B.Fab")
		)
		(pad "1" smd rect
			(at 0.2667 0 180)
			(size 0.3048 0.381)
			(layers "B.Cu" "B.Mask" "B.Paste")
			(net "P12V_NIC5")
		)
		(pad "2" smd rect
			(at -0.2667 0 180)
			(size 0.3048 0.381)
			(layers "B.Cu" "B.Mask" "B.Paste")
			(net "GND")
		)
	)
	(footprint ""
		(layer "B.Cu")
		(at 412.224982 -293.99992 -90)
		(property "Reference" "C1911"
			(at 0 0 90)
			(layer "B.SilkS")
			(hide yes)
			(effects
				(font
					(size 1.27 1.27)
				)
				(justify mirror)
			)
		)
		(property "Value" ""
			(at 0 0 90)
			(layer "B.Fab")
			(effects
				(font
					(size 1.27 1.27)
				)
				(justify mirror)
			)
		)
		(duplicate_pad_numbers_are_jumpers no)
		(fp_line
			(start -0.299974 0.150114)
			(end 0.299974 0.150114)
			(stroke
				(width 0.1)
				(type default)
			)
			(layer "B.Fab")
		)
		(fp_line
			(start 0.299974 0.150114)
			(end 0.299974 -0.150114)
			(stroke
				(width 0.1)
				(type default)
			)
			(layer "B.Fab")
		)
		(fp_line
			(start -0.299974 -0.150114)
			(end -0.299974 0.150114)
			(stroke
				(width 0.1)
				(type default)
			)
			(layer "B.Fab")
		)
		(fp_line
			(start 0.299974 -0.150114)
			(end -0.299974 -0.150114)
			(stroke
				(width 0.1)
				(type default)
			)
			(layer "B.Fab")
		)
		(pad "1" smd rect
			(at 0.2667 0 90)
			(size 0.3048 0.381)
			(layers "B.Cu" "B.Mask" "B.Paste")
			(net "P0V8_PEX3")
		)
		(pad "2" smd rect
			(at -0.2667 0 90)
			(size 0.3048 0.381)
			(layers "B.Cu" "B.Mask" "B.Paste")
			(net "GND")
		)
	)
	(footprint ""
		(layer "B.Cu")
		(at 421.249856 -293.99992 180)
		(property "Reference" "C3471"
			(at 0 0 0)
			(layer "B.SilkS")
			(hide yes)
			(effects
				(font
					(size 1.27 1.27)
				)
				(justify mirror)
			)
		)
		(property "Value" ""
			(at 0 0 0)
			(layer "B.Fab")
			(effects
				(font
					(size 1.27 1.27)
				)
				(justify mirror)
			)
		)
		(duplicate_pad_numbers_are_jumpers no)
		(fp_line
			(start 0.299974 0.150114)
			(end 0.299974 -0.150114)
			(stroke
				(width 0.1)
				(type default)
			)
			(layer "B.Fab")
		)
		(fp_line
			(start 0.299974 -0.150114)
			(end -0.299974 -0.150114)
			(stroke
				(width 0.1)
				(type default)
			)
			(layer "B.Fab")
		)
		(fp_line
			(start -0.299974 0.150114)
			(end 0.299974 0.150114)
			(stroke
				(width 0.1)
				(type default)
			)
			(layer "B.Fab")
		)
		(fp_line
			(start -0.299974 -0.150114)
			(end -0.299974 0.150114)
			(stroke
				(width 0.1)
				(type default)
			)
			(layer "B.Fab")
		)
		(pad "1" smd rect
			(at 0.2667 0)
			(size 0.3048 0.381)
			(layers "B.Cu" "B.Mask" "B.Paste")
			(net "P1V25_SERDES_VDDPLL_PEX3")
		)
		(pad "2" smd rect
			(at -0.2667 0)
			(size 0.3048 0.381)
			(layers "B.Cu" "B.Mask" "B.Paste")
			(net "GND")
		)
	)
	(footprint ""
		(layer "B.Cu")
		(at 187.149994 -294.4749 180)
		(property "Reference" "C3114"
			(at 0 0 0)
			(layer "B.SilkS")
			(hide yes)
			(effects
				(font
					(size 1.27 1.27)
				)
				(justify mirror)
			)
		)
		(property "Value" ""
			(at 0 0 0)
			(layer "B.Fab")
			(effects
				(font
					(size 1.27 1.27)
				)
				(justify mirror)
			)
		)
		(duplicate_pad_numbers_are_jumpers no)
		(fp_line
			(start 0.299974 0.150114)
			(end 0.299974 -0.150114)
			(stroke
				(width 0.1)
				(type default)
			)
			(layer "B.Fab")
		)
		(fp_line
			(start 0.299974 -0.150114)
			(end -0.299974 -0.150114)
			(stroke
				(width 0.1)
				(type default)
			)
			(layer "B.Fab")
		)
		(fp_line
			(start -0.299974 0.150114)
			(end 0.299974 0.150114)
			(stroke
				(width 0.1)
				(type default)
			)
			(layer "B.Fab")
		)
		(fp_line
			(start -0.299974 -0.150114)
			(end -0.299974 0.150114)
			(stroke
				(width 0.1)
				(type default)
			)
			(layer "B.Fab")
		)
		(pad "1" smd rect
			(at 0.2667 0)
			(size 0.3048 0.381)
			(layers "B.Cu" "B.Mask" "B.Paste")
			(net "P1V25_PEX1")
		)
		(pad "2" smd rect
			(at -0.2667 0)
			(size 0.3048 0.381)
			(layers "B.Cu" "B.Mask" "B.Paste")
			(net "GND")
		)
	)
	(footprint ""
		(layer "B.Cu")
		(at 329.692 -221.4372 180)
		(property "Reference" "R4173"
			(at 0 0 0)
			(layer "B.SilkS")
			(hide yes)
			(effects
				(font
					(size 1.27 1.27)
				)
				(justify mirror)
			)
		)
		(property "Value" ""
			(at 0 0 0)
			(layer "B.Fab")
			(effects
				(font
					(size 1.27 1.27)
				)
				(justify mirror)
			)
		)
		(duplicate_pad_numbers_are_jumpers no)
		(fp_line
			(start 0.7874 0.4064)
			(end 0.7874 -0.4064)
			(stroke
				(width 0.1524)
				(type default)
			)
			(layer "B.SilkS")
		)
		(fp_line
			(start 0.7874 -0.4064)
			(end -0.7874 -0.4064)
			(stroke
				(width 0.1524)
				(type default)
			)
			(layer "B.SilkS")
		)
		(fp_line
			(start -0.7874 0.4064)
			(end 0.7874 0.4064)
			(stroke
				(width 0.1524)
				(type default)
			)
			(layer "B.SilkS")
		)
		(fp_line
			(start -0.7874 -0.4064)
			(end -0.7874 0.4064)
			(stroke
				(width 0.1524)
				(type default)
			)
			(layer "B.SilkS")
		)
		(fp_line
			(start 0.67945 0.3048)
			(end 0.67945 -0.305054)
			(stroke
				(width 0.1)
				(type default)
			)
			(layer "B.Fab")
		)
		(fp_line
			(start 0.67945 -0.305054)
			(end 0.12065 -0.305054)
			(stroke
				(width 0.1)
				(type default)
			)
			(layer "B.Fab")
		)
		(fp_line
			(start 0.12065 0.3048)
			(end 0.67945 0.3048)
			(stroke
				(width 0.1)
				(type default)
			)
			(layer "B.Fab")
		)
		(fp_line
			(start 0.12065 0.2794)
			(end 0.12065 0.3048)
			(stroke
				(width 0.1)
				(type default)
			)
			(layer "B.Fab")
		)
		(fp_line
			(start 0.12065 -0.2794)
			(end -0.12065 -0.2794)
			(stroke
				(width 0.1)
				(type default)
			)
			(layer "B.Fab")
		)
		(fp_line
			(start 0.12065 -0.305054)
			(end 0.12065 -0.2794)
			(stroke
				(width 0.1)
				(type default)
			)
			(layer "B.Fab")
		)
		(fp_line
			(start -0.120396 0.3048)
			(end -0.120396 0.2794)
			(stroke
				(width 0.1)
				(type default)
			)
			(layer "B.Fab")
		)
		(fp_line
			(start -0.120396 0.2794)
			(end 0.12065 0.2794)
			(stroke
				(width 0.1)
				(type default)
			)
			(layer "B.Fab")
		)
		(fp_line
			(start -0.12065 -0.2794)
			(end -0.12065 -0.3048)
			(stroke
				(width 0.1)
				(type default)
			)
			(layer "B.Fab")
		)
		(fp_line
			(start -0.12065 -0.3048)
			(end -0.67945 -0.3048)
			(stroke
				(width 0.1)
				(type default)
			)
			(layer "B.Fab")
		)
		(fp_line
			(start -0.67945 0.3048)
			(end -0.120396 0.3048)
			(stroke
				(width 0.1)
				(type default)
			)
			(layer "B.Fab")
		)
		(fp_line
			(start -0.67945 -0.3048)
			(end -0.67945 0.3048)
			(stroke
				(width 0.1)
				(type default)
			)
			(layer "B.Fab")
		)
		(pad "1" smd circle
			(at 0.40005 0)
			(size 0 0)
			(layers "B.Cu" "B.Mask" "B.Paste")
			(net "RST_PEX2_PERST_R_N")
		)
		(pad "2" smd circle
			(at -0.40005 0)
			(size 0 0)
			(layers "B.Cu" "B.Mask" "B.Paste")
			(net "RST_PEX2_PERST_N")
		)
	)
	(footprint ""
		(layer "B.Cu")
		(at 399.874994 -286.399732 90)
		(property "Reference" "C3502"
			(at 0 0 90)
			(layer "B.SilkS")
			(hide yes)
			(effects
				(font
					(size 1.27 1.27)
				)
				(justify mirror)
			)
		)
		(property "Value" ""
			(at 0 0 90)
			(layer "B.Fab")
			(effects
				(font
					(size 1.27 1.27)
				)
				(justify mirror)
			)
		)
		(duplicate_pad_numbers_are_jumpers no)
		(fp_line
			(start 0.299974 -0.150114)
			(end -0.299974 -0.150114)
			(stroke
				(width 0.1)
				(type default)
			)
			(layer "B.Fab")
		)
		(fp_line
			(start -0.299974 -0.150114)
			(end -0.299974 0.150114)
			(stroke
				(width 0.1)
				(type default)
			)
			(layer "B.Fab")
		)
		(fp_line
			(start 0.299974 0.150114)
			(end 0.299974 -0.150114)
			(stroke
				(width 0.1)
				(type default)
			)
			(layer "B.Fab")
		)
		(fp_line
			(start -0.299974 0.150114)
			(end 0.299974 0.150114)
			(stroke
				(width 0.1)
				(type default)
			)
			(layer "B.Fab")
		)
		(pad "1" smd rect
			(at 0.2667 0 270)
			(size 0.3048 0.381)
			(layers "B.Cu" "B.Mask" "B.Paste")
			(net "P1V25_SERDES_VDDPLL_PEX3")
		)
		(pad "2" smd rect
			(at -0.2667 0 270)
			(size 0.3048 0.381)
			(layers "B.Cu" "B.Mask" "B.Paste")
			(net "GND")
		)
	)
	(footprint ""
		(layer "B.Cu")
		(at 298.499784 -292.099746 90)
		(property "Reference" "C1699"
			(at 0 0 90)
			(layer "B.SilkS")
			(hide yes)
			(effects
				(font
					(size 1.27 1.27)
				)
				(justify mirror)
			)
		)
		(property "Value" ""
			(at 0 0 90)
			(layer "B.Fab")
			(effects
				(font
					(size 1.27 1.27)
				)
				(justify mirror)
			)
		)
		(duplicate_pad_numbers_are_jumpers no)
		(fp_line
			(start 0.299974 -0.150114)
			(end -0.299974 -0.150114)
			(stroke
				(width 0.1)
				(type default)
			)
			(layer "B.Fab")
		)
		(fp_line
			(start -0.299974 -0.150114)
			(end -0.299974 0.150114)
			(stroke
				(width 0.1)
				(type default)
			)
			(layer "B.Fab")
		)
		(fp_line
			(start 0.299974 0.150114)
			(end 0.299974 -0.150114)
			(stroke
				(width 0.1)
				(type default)
			)
			(layer "B.Fab")
		)
		(fp_line
			(start -0.299974 0.150114)
			(end 0.299974 0.150114)
			(stroke
				(width 0.1)
				(type default)
			)
			(layer "B.Fab")
		)
		(pad "1" smd rect
			(at 0.2667 0 270)
			(size 0.3048 0.381)
			(layers "B.Cu" "B.Mask" "B.Paste")
			(net "P0V8_SERDES_VDDA_PEX2")
		)
		(pad "2" smd rect
			(at -0.2667 0 270)
			(size 0.3048 0.381)
			(layers "B.Cu" "B.Mask" "B.Paste")
			(net "GND")
		)
	)
)
